(kicad_pcb
	(version 20260206)
	(generator "pcbnew")
	(generator_version "10.0")
	(general
		(thickness 1.6)
		(legacy_teardrops no)
	)
	(paper "A4")
	(title_block
		(title "03242023_DA0F0TMBIJ0_F0T_Motherboard_J_brd_V01_OCP.brd")
		(comment 1 "Grand Teton / footprints 5329-5335 of 6105")
	)
	(layers
		(0 "F.Cu" signal "TOP")
		(4 "In1.Cu" signal "GND")
		(6 "In2.Cu" signal "IN1")
		(8 "In3.Cu" signal "GND1")
		(10 "In4.Cu" signal "IN2")
		(12 "In5.Cu" signal "GND2")
		(14 "In6.Cu" signal "IN3")
		(16 "In7.Cu" signal "GND3")
		(18 "In8.Cu" signal "VCC")
		(20 "In9.Cu" signal "VCC1")
		(22 "In10.Cu" signal "GND4")
		(24 "In11.Cu" signal "IN4")
		(26 "In12.Cu" signal "GND5")
		(28 "In13.Cu" signal "IN5")
		(30 "In14.Cu" signal "GND6")
		(32 "In15.Cu" signal "IN6")
		(34 "In16.Cu" signal "GND7")
		(2 "B.Cu" signal "BOTTOM")
		(9 "F.Adhes" user "F.Adhesive")
		(11 "B.Adhes" user "B.Adhesive")
		(13 "F.Paste" user "Package Geometry/Pastemask Top")
		(15 "B.Paste" user "Package Geometry/Pastemask Bottom")
		(5 "F.SilkS" user "Ref Des/Silkscreen Top")
		(7 "B.SilkS" user "Ref Des/Silkscreen Bottom")
		(1 "F.Mask" user "Board Geometry/Soldermask Top")
		(3 "B.Mask" user "Board Geometry/Soldermask Bottom")
		(17 "Dwgs.User" user "User.Drawings")
		(19 "Cmts.User" user "User.Comments")
		(21 "Eco1.User" user "User.Eco1")
		(23 "Eco2.User" user "User.Eco2")
		(25 "Edge.Cuts" user "Board Geometry/Outline")
		(27 "Margin" user)
		(31 "F.CrtYd" user "Package Geometry/Place Bound Top")
		(29 "B.CrtYd" user "Package Geometry/Place Bound Bottom")
		(35 "F.Fab" user "Ref Des/Assembly Top")
		(33 "B.Fab" user "Ref Des/Assembly Bottom")
	)
	(footprint ""
		(layer "B.Cu")
		(at 407.91257 -158.714948 180)
		(property "Reference" "PC1"
			(at 0 0 0)
			(layer "B.SilkS")
			(hide yes)
			(effects
				(font
					(size 1.27 1.27)
				)
				(justify mirror)
			)
		)
		(property "Value" ""
			(at 0 0 0)
			(layer "B.Fab")
			(effects
				(font
					(size 1.27 1.27)
				)
				(justify mirror)
			)
		)
		(duplicate_pad_numbers_are_jumpers no)
		(fp_line
			(start 1.524 0.762)
			(end 1.524 -0.762)
			(stroke
				(width 0.1524)
				(type default)
			)
			(layer "B.SilkS")
		)
		(fp_line
			(start 1.524 -0.762)
			(end -1.524 -0.762)
			(stroke
				(width 0.1524)
				(type default)
			)
			(layer "B.SilkS")
		)
		(fp_line
			(start -1.524 0.762)
			(end 1.524 0.762)
			(stroke
				(width 0.1524)
				(type default)
			)
			(layer "B.SilkS")
		)
		(fp_line
			(start -1.524 -0.762)
			(end -1.524 0.762)
			(stroke
				(width 0.1524)
				(type default)
			)
			(layer "B.SilkS")
		)
		(fp_line
			(start 1.1049 0.724916)
			(end -1.1049 0.724916)
			(stroke
				(width 0.1)
				(type default)
			)
			(layer "B.Fab")
		)
		(fp_line
			(start 1.1049 -0.724916)
			(end 1.1049 0.724916)
			(stroke
				(width 0.1)
				(type default)
			)
			(layer "B.Fab")
		)
		(fp_line
			(start -1.1049 0.724916)
			(end -1.1049 -0.724916)
			(stroke
				(width 0.1)
				(type default)
			)
			(layer "B.Fab")
		)
		(fp_line
			(start -1.1049 -0.724916)
			(end 1.1049 -0.724916)
			(stroke
				(width 0.1)
				(type default)
			)
			(layer "B.Fab")
		)
		(pad "1" smd rect
			(at 0.889 0 180)
			(size 1.016 1.27)
			(layers "B.Cu" "B.Mask" "B.Paste")
			(net "PVCCD_HV_CPU0")
		)
		(pad "2" smd rect
			(at -0.889 0 180)
			(size 1.016 1.27)
			(layers "B.Cu" "B.Mask" "B.Paste")
			(net "GND")
		)
	)
	(footprint ""
		(layer "B.Cu")
		(at 16.208502 -98.669348)
		(property "Reference" "C2032"
			(at 0 0 0)
			(layer "B.SilkS")
			(hide yes)
			(effects
				(font
					(size 1.27 1.27)
				)
				(justify mirror)
			)
		)
		(property "Value" ""
			(at 0 0 0)
			(layer "B.Fab")
			(effects
				(font
					(size 1.27 1.27)
				)
				(justify mirror)
			)
		)
		(duplicate_pad_numbers_are_jumpers no)
		(fp_line
			(start -0.7874 -0.4064)
			(end -0.7874 0.4064)
			(stroke
				(width 0.1524)
				(type default)
			)
			(layer "B.SilkS")
		)
		(fp_line
			(start -0.7874 0.4064)
			(end 0.7874 0.4064)
			(stroke
				(width 0.1524)
				(type default)
			)
			(layer "B.SilkS")
		)
		(fp_line
			(start 0.7874 -0.4064)
			(end -0.7874 -0.4064)
			(stroke
				(width 0.1524)
				(type default)
			)
			(layer "B.SilkS")
		)
		(fp_line
			(start 0.7874 0.4064)
			(end 0.7874 -0.4064)
			(stroke
				(width 0.1524)
				(type default)
			)
			(layer "B.SilkS")
		)
		(fp_line
			(start -0.67945 -0.3048)
			(end -0.67945 0.3048)
			(stroke
				(width 0.1)
				(type default)
			)
			(layer "B.Fab")
		)
		(fp_line
			(start -0.67945 0.3048)
			(end -0.120396 0.3048)
			(stroke
				(width 0.1)
				(type default)
			)
			(layer "B.Fab")
		)
		(fp_line
			(start -0.12065 -0.3048)
			(end -0.67945 -0.3048)
			(stroke
				(width 0.1)
				(type default)
			)
			(layer "B.Fab")
		)
		(fp_line
			(start -0.12065 -0.2794)
			(end -0.12065 -0.3048)
			(stroke
				(width 0.1)
				(type default)
			)
			(layer "B.Fab")
		)
		(fp_line
			(start -0.120396 0.2794)
			(end 0.12065 0.2794)
			(stroke
				(width 0.1)
				(type default)
			)
			(layer "B.Fab")
		)
		(fp_line
			(start -0.120396 0.3048)
			(end -0.120396 0.2794)
			(stroke
				(width 0.1)
				(type default)
			)
			(layer "B.Fab")
		)
		(fp_line
			(start 0.12065 -0.305054)
			(end 0.12065 -0.2794)
			(stroke
				(width 0.1)
				(type default)
			)
			(layer "B.Fab")
		)
		(fp_line
			(start 0.12065 -0.2794)
			(end -0.12065 -0.2794)
			(stroke
				(width 0.1)
				(type default)
			)
			(layer "B.Fab")
		)
		(fp_line
			(start 0.12065 0.2794)
			(end 0.12065 0.3048)
			(stroke
				(width 0.1)
				(type default)
			)
			(layer "B.Fab")
		)
		(fp_line
			(start 0.12065 0.3048)
			(end 0.67945 0.3048)
			(stroke
				(width 0.1)
				(type default)
			)
			(layer "B.Fab")
		)
		(fp_line
			(start 0.67945 -0.305054)
			(end 0.12065 -0.305054)
			(stroke
				(width 0.1)
				(type default)
			)
			(layer "B.Fab")
		)
		(fp_line
			(start 0.67945 0.3048)
			(end 0.67945 -0.305054)
			(stroke
				(width 0.1)
				(type default)
			)
			(layer "B.Fab")
		)
		(pad "1" smd circle
			(at 0.40005 0 180)
			(size 0 0)
			(layers "B.Cu" "B.Mask" "B.Paste")
			(net "P3V3_AUX_USB_HUB")
		)
		(pad "2" smd circle
			(at -0.40005 0 180)
			(size 0 0)
			(layers "B.Cu" "B.Mask" "B.Paste")
			(net "GND")
		)
	)
	(footprint ""
		(layer "B.Cu")
		(at 63.017908 -258.465066 -90)
		(property "Reference" "C454"
			(at 0 0 90)
			(layer "B.SilkS")
			(hide yes)
			(effects
				(font
					(size 1.27 1.27)
				)
				(justify mirror)
			)
		)
		(property "Value" ""
			(at 0 0 90)
			(layer "B.Fab")
			(effects
				(font
					(size 1.27 1.27)
				)
				(justify mirror)
			)
		)
		(duplicate_pad_numbers_are_jumpers no)
		(fp_line
			(start -1.524 0.762)
			(end 1.524 0.762)
			(stroke
				(width 0.1524)
				(type default)
			)
			(layer "B.SilkS")
		)
		(fp_line
			(start 1.524 0.762)
			(end 1.524 -0.762)
			(stroke
				(width 0.1524)
				(type default)
			)
			(layer "B.SilkS")
		)
		(fp_line
			(start -1.524 -0.762)
			(end -1.524 0.762)
			(stroke
				(width 0.1524)
				(type default)
			)
			(layer "B.SilkS")
		)
		(fp_line
			(start 1.524 -0.762)
			(end -1.524 -0.762)
			(stroke
				(width 0.1524)
				(type default)
			)
			(layer "B.SilkS")
		)
		(fp_line
			(start -1.1049 0.724916)
			(end -1.1049 -0.724916)
			(stroke
				(width 0.1)
				(type default)
			)
			(layer "B.Fab")
		)
		(fp_line
			(start 1.1049 0.724916)
			(end -1.1049 0.724916)
			(stroke
				(width 0.1)
				(type default)
			)
			(layer "B.Fab")
		)
		(fp_line
			(start -1.1049 -0.724916)
			(end 1.1049 -0.724916)
			(stroke
				(width 0.1)
				(type default)
			)
			(layer "B.Fab")
		)
		(fp_line
			(start 1.1049 -0.724916)
			(end 1.1049 0.724916)
			(stroke
				(width 0.1)
				(type default)
			)
			(layer "B.Fab")
		)
		(pad "1" smd rect
			(at 0.889 0 270)
			(size 1.016 1.27)
			(layers "B.Cu" "B.Mask" "B.Paste")
			(net "PVCCFA_EHV_FIVRA_CPU1")
		)
		(pad "2" smd rect
			(at -0.889 0 270)
			(size 1.016 1.27)
			(layers "B.Cu" "B.Mask" "B.Paste")
			(net "GND")
		)
	)
	(footprint ""
		(layer "B.Cu")
		(at 241.3254 -422.9862 90)
		(property "Reference" "R2803"
			(at 0 0 90)
			(layer "B.SilkS")
			(hide yes)
			(effects
				(font
					(size 1.27 1.27)
				)
				(justify mirror)
			)
		)
		(property "Value" ""
			(at 0 0 90)
			(layer "B.Fab")
			(effects
				(font
					(size 1.27 1.27)
				)
				(justify mirror)
			)
		)
		(duplicate_pad_numbers_are_jumpers no)
		(fp_line
			(start 0.7874 -0.4064)
			(end -0.7874 -0.4064)
			(stroke
				(width 0.1524)
				(type default)
			)
			(layer "B.SilkS")
		)
		(fp_line
			(start -0.7874 -0.4064)
			(end -0.7874 0.4064)
			(stroke
				(width 0.1524)
				(type default)
			)
			(layer "B.SilkS")
		)
		(fp_line
			(start 0.7874 0.4064)
			(end 0.7874 -0.4064)
			(stroke
				(width 0.1524)
				(type default)
			)
			(layer "B.SilkS")
		)
		(fp_line
			(start -0.7874 0.4064)
			(end 0.7874 0.4064)
			(stroke
				(width 0.1524)
				(type default)
			)
			(layer "B.SilkS")
		)
		(fp_line
			(start 0.67945 -0.305054)
			(end 0.12065 -0.305054)
			(stroke
				(width 0.1)
				(type default)
			)
			(layer "B.Fab")
		)
		(fp_line
			(start 0.12065 -0.305054)
			(end 0.12065 -0.2794)
			(stroke
				(width 0.1)
				(type default)
			)
			(layer "B.Fab")
		)
		(fp_line
			(start -0.12065 -0.3048)
			(end -0.67945 -0.3048)
			(stroke
				(width 0.1)
				(type default)
			)
			(layer "B.Fab")
		)
		(fp_line
			(start -0.67945 -0.3048)
			(end -0.67945 0.3048)
			(stroke
				(width 0.1)
				(type default)
			)
			(layer "B.Fab")
		)
		(fp_line
			(start 0.12065 -0.2794)
			(end -0.12065 -0.2794)
			(stroke
				(width 0.1)
				(type default)
			)
			(layer "B.Fab")
		)
		(fp_line
			(start -0.12065 -0.2794)
			(end -0.12065 -0.3048)
			(stroke
				(width 0.1)
				(type default)
			)
			(layer "B.Fab")
		)
		(fp_line
			(start 0.12065 0.2794)
			(end 0.12065 0.3048)
			(stroke
				(width 0.1)
				(type default)
			)
			(layer "B.Fab")
		)
		(fp_line
			(start -0.120396 0.2794)
			(end 0.12065 0.2794)
			(stroke
				(width 0.1)
				(type default)
			)
			(layer "B.Fab")
		)
		(fp_line
			(start 0.67945 0.3048)
			(end 0.67945 -0.305054)
			(stroke
				(width 0.1)
				(type default)
			)
			(layer "B.Fab")
		)
		(fp_line
			(start 0.12065 0.3048)
			(end 0.67945 0.3048)
			(stroke
				(width 0.1)
				(type default)
			)
			(layer "B.Fab")
		)
		(fp_line
			(start -0.120396 0.3048)
			(end -0.120396 0.2794)
			(stroke
				(width 0.1)
				(type default)
			)
			(layer "B.Fab")
		)
		(fp_line
			(start -0.67945 0.3048)
			(end -0.120396 0.3048)
			(stroke
				(width 0.1)
				(type default)
			)
			(layer "B.Fab")
		)
		(pad "1" smd circle
			(at 0.40005 0 270)
			(size 0 0)
			(layers "B.Cu" "B.Mask" "B.Paste")
			(net "FM_FAN_PWR_EN_R")
		)
		(pad "2" smd circle
			(at -0.40005 0 270)
			(size 0 0)
			(layers "B.Cu" "B.Mask" "B.Paste")
			(net "FM_FAN_PWR_EN")
		)
	)
	(footprint ""
		(layer "B.Cu")
		(at 364.5154 -333.73568 90)
		(property "Reference" "PC283_P0_3"
			(at 0 0 90)
			(layer "B.SilkS")
			(hide yes)
			(effects
				(font
					(size 1.27 1.27)
				)
				(justify mirror)
			)
		)
		(property "Value" ""
			(at 0 0 90)
			(layer "B.Fab")
			(effects
				(font
					(size 1.27 1.27)
				)
				(justify mirror)
			)
		)
		(duplicate_pad_numbers_are_jumpers no)
		(fp_line
			(start 1.524 -0.762)
			(end -1.524 -0.762)
			(stroke
				(width 0.1524)
				(type default)
			)
			(layer "B.SilkS")
		)
		(fp_line
			(start -1.524 -0.762)
			(end -1.524 0.762)
			(stroke
				(width 0.1524)
				(type default)
			)
			(layer "B.SilkS")
		)
		(fp_line
			(start 1.524 0.762)
			(end 1.524 -0.762)
			(stroke
				(width 0.1524)
				(type default)
			)
			(layer "B.SilkS")
		)
		(fp_line
			(start -1.524 0.762)
			(end 1.524 0.762)
			(stroke
				(width 0.1524)
				(type default)
			)
			(layer "B.SilkS")
		)
		(fp_line
			(start 1.1049 -0.724916)
			(end 1.1049 0.724916)
			(stroke
				(width 0.1)
				(type default)
			)
			(layer "B.Fab")
		)
		(fp_line
			(start -1.1049 -0.724916)
			(end 1.1049 -0.724916)
			(stroke
				(width 0.1)
				(type default)
			)
			(layer "B.Fab")
		)
		(fp_line
			(start 1.1049 0.724916)
			(end -1.1049 0.724916)
			(stroke
				(width 0.1)
				(type default)
			)
			(layer "B.Fab")
		)
		(fp_line
			(start -1.1049 0.724916)
			(end -1.1049 -0.724916)
			(stroke
				(width 0.1)
				(type default)
			)
			(layer "B.Fab")
		)
		(pad "1" smd rect
			(at 0.889 0 90)
			(size 1.016 1.27)
			(layers "B.Cu" "B.Mask" "B.Paste")
			(net "SW_P12V_PVCCIN_CPU0_FLT")
		)
		(pad "2" smd rect
			(at -0.889 0 90)
			(size 1.016 1.27)
			(layers "B.Cu" "B.Mask" "B.Paste")
			(net "GND")
		)
	)
	(footprint ""
		(layer "B.Cu")
		(at 242.2906 -422.9862 90)
		(property "Reference" "R4701"
			(at 0 0 90)
			(layer "B.SilkS")
			(hide yes)
			(effects
				(font
					(size 1.27 1.27)
				)
				(justify mirror)
			)
		)
		(property "Value" ""
			(at 0 0 90)
			(layer "B.Fab")
			(effects
				(font
					(size 1.27 1.27)
				)
				(justify mirror)
			)
		)
		(duplicate_pad_numbers_are_jumpers no)
		(fp_line
			(start 0.7874 -0.4064)
			(end -0.7874 -0.4064)
			(stroke
				(width 0.1524)
				(type default)
			)
			(layer "B.SilkS")
		)
		(fp_line
			(start -0.7874 -0.4064)
			(end -0.7874 0.4064)
			(stroke
				(width 0.1524)
				(type default)
			)
			(layer "B.SilkS")
		)
		(fp_line
			(start 0.7874 0.4064)
			(end 0.7874 -0.4064)
			(stroke
				(width 0.1524)
				(type default)
			)
			(layer "B.SilkS")
		)
		(fp_line
			(start -0.7874 0.4064)
			(end 0.7874 0.4064)
			(stroke
				(width 0.1524)
				(type default)
			)
			(layer "B.SilkS")
		)
		(fp_line
			(start 0.67945 -0.305054)
			(end 0.12065 -0.305054)
			(stroke
				(width 0.1)
				(type default)
			)
			(layer "B.Fab")
		)
		(fp_line
			(start 0.12065 -0.305054)
			(end 0.12065 -0.2794)
			(stroke
				(width 0.1)
				(type default)
			)
			(layer "B.Fab")
		)
		(fp_line
			(start -0.12065 -0.3048)
			(end -0.67945 -0.3048)
			(stroke
				(width 0.1)
				(type default)
			)
			(layer "B.Fab")
		)
		(fp_line
			(start -0.67945 -0.3048)
			(end -0.67945 0.3048)
			(stroke
				(width 0.1)
				(type default)
			)
			(layer "B.Fab")
		)
		(fp_line
			(start 0.12065 -0.2794)
			(end -0.12065 -0.2794)
			(stroke
				(width 0.1)
				(type default)
			)
			(layer "B.Fab")
		)
		(fp_line
			(start -0.12065 -0.2794)
			(end -0.12065 -0.3048)
			(stroke
				(width 0.1)
				(type default)
			)
			(layer "B.Fab")
		)
		(fp_line
			(start 0.12065 0.2794)
			(end 0.12065 0.3048)
			(stroke
				(width 0.1)
				(type default)
			)
			(layer "B.Fab")
		)
		(fp_line
			(start -0.120396 0.2794)
			(end 0.12065 0.2794)
			(stroke
				(width 0.1)
				(type default)
			)
			(layer "B.Fab")
		)
		(fp_line
			(start 0.67945 0.3048)
			(end 0.67945 -0.305054)
			(stroke
				(width 0.1)
				(type default)
			)
			(layer "B.Fab")
		)
		(fp_line
			(start 0.12065 0.3048)
			(end 0.67945 0.3048)
			(stroke
				(width 0.1)
				(type default)
			)
			(layer "B.Fab")
		)
		(fp_line
			(start -0.120396 0.3048)
			(end -0.120396 0.2794)
			(stroke
				(width 0.1)
				(type default)
			)
			(layer "B.Fab")
		)
		(fp_line
			(start -0.67945 0.3048)
			(end -0.120396 0.3048)
			(stroke
				(width 0.1)
				(type default)
			)
			(layer "B.Fab")
		)
		(pad "1" smd circle
			(at 0.40005 0 270)
			(size 0 0)
			(layers "B.Cu" "B.Mask" "B.Paste")
			(net "P3V3_AUX")
		)
		(pad "2" smd circle
			(at -0.40005 0 270)
			(size 0 0)
			(layers "B.Cu" "B.Mask" "B.Paste")
			(net "FM_FAN_PWR_EN")
		)
	)
	(footprint ""
		(layer "B.Cu")
		(at 92.333572 -328.298048 -90)
		(property "Reference" "PC521_P1_6"
			(at 0 0 90)
			(layer "B.SilkS")
			(hide yes)
			(effects
				(font
					(size 1.27 1.27)
				)
				(justify mirror)
			)
		)
		(property "Value" ""
			(at 0 0 90)
			(layer "B.Fab")
			(effects
				(font
					(size 1.27 1.27)
				)
				(justify mirror)
			)
		)
		(duplicate_pad_numbers_are_jumpers no)
		(fp_line
			(start -1.524 0.762)
			(end 1.524 0.762)
			(stroke
				(width 0.1524)
				(type default)
			)
			(layer "B.SilkS")
		)
		(fp_line
			(start 1.524 0.762)
			(end 1.524 -0.762)
			(stroke
				(width 0.1524)
				(type default)
			)
			(layer "B.SilkS")
		)
		(fp_line
			(start -1.524 -0.762)
			(end -1.524 0.762)
			(stroke
				(width 0.1524)
				(type default)
			)
			(layer "B.SilkS")
		)
		(fp_line
			(start 1.524 -0.762)
			(end -1.524 -0.762)
			(stroke
				(width 0.1524)
				(type default)
			)
			(layer "B.SilkS")
		)
		(fp_line
			(start -1.1049 0.724916)
			(end -1.1049 -0.724916)
			(stroke
				(width 0.1)
				(type default)
			)
			(layer "B.Fab")
		)
		(fp_line
			(start 1.1049 0.724916)
			(end -1.1049 0.724916)
			(stroke
				(width 0.1)
				(type default)
			)
			(layer "B.Fab")
		)
		(fp_line
			(start -1.1049 -0.724916)
			(end 1.1049 -0.724916)
			(stroke
				(width 0.1)
				(type default)
			)
			(layer "B.Fab")
		)
		(fp_line
			(start 1.1049 -0.724916)
			(end 1.1049 0.724916)
			(stroke
				(width 0.1)
				(type default)
			)
			(layer "B.Fab")
		)
		(pad "1" smd rect
			(at 0.889 0 270)
			(size 1.016 1.27)
			(layers "B.Cu" "B.Mask" "B.Paste")
			(net "PVCCIN_CPU1")
		)
		(pad "2" smd rect
			(at -0.889 0 270)
			(size 1.016 1.27)
			(layers "B.Cu" "B.Mask" "B.Paste")
			(net "GND")
		)
	)
)
